# BASEBOARD_FAB2 (Tioga Pass) — schematic netlist excerpt (pin names and nets, part order shuffled) for the footprints in the layout excerpt that follows; sources: Cadence DE-HDL packaged netlist, KiCad conversion of Wiwynn_Tioga_Pass_MB.brd

R8B14  RES  0.0 5% CHIP  pkg 0402  page 236 : A = VSENSE_P1V05_PCH_STBY_AVSP ; B = P1V05_PCH_STBY
R1M8  RES  20.0 1% CHIP  pkg 0402  page 167 : A = SMB_SENSOR_TMP421_1_SCL ; B = SMB_SENSOR_STBY_LVC3_SCL
R3D9  RES  49.9 1% CHIP  pkg 0402  page 90 : A = PD_CPU1_TEST12 ; B = GND

(kicad_pcb
	(version 20260206)
	(generator "pcbnew")
	(generator_version "10.0")
	(general
		(thickness 1.6)
		(legacy_teardrops no)
	)
	(paper "A4")
	(title_block
		(title "Wiwynn_Tioga_Pass_MB.brd")
		(comment 1 "Tioga Pass / footprints 1972-1974 of 4770")
	)
	(layers
		(0 "F.Cu" signal "TOP")
		(4 "In1.Cu" signal "L2GND")
		(6 "In2.Cu" signal "L3")
		(8 "In3.Cu" signal "L4GND")
		(10 "In4.Cu" signal "L5")
		(12 "In5.Cu" signal "L6GND")
		(14 "In6.Cu" signal "L7VCC")
		(16 "In7.Cu" signal "L8VCC")
		(18 "In8.Cu" signal "L9GND")
		(20 "In9.Cu" signal "L10")
		(22 "In10.Cu" signal "L11GND")
		(24 "In11.Cu" signal "L12")
		(26 "In12.Cu" signal "L13GND")
		(2 "B.Cu" signal "BOTTOM")
		(9 "F.Adhes" user "F.Adhesive")
		(11 "B.Adhes" user "B.Adhesive")
		(13 "F.Paste" user "Package Geometry/Pastemask Top")
		(15 "B.Paste" user "Package Geometry/Pastemask Bottom")
		(5 "F.SilkS" user "Ref Des/Silkscreen Top")
		(7 "B.SilkS" user "Ref Des/Silkscreen Bottom")
		(1 "F.Mask" user "Board Geometry/Soldermask Top")
		(3 "B.Mask" user "Board Geometry/Soldermask Bottom")
		(17 "Dwgs.User" user "User.Drawings")
		(19 "Cmts.User" user "User.Comments")
		(21 "Eco1.User" user "User.Eco1")
		(23 "Eco2.User" user "User.Eco2")
		(25 "Edge.Cuts" user "Board Geometry/Outline")
		(27 "Margin" user)
		(31 "F.CrtYd" user "Package Geometry/Place Bound Top")
		(29 "B.CrtYd" user "Package Geometry/Place Bound Bottom")
		(35 "F.Fab" user "Ref Des/Assembly Top")
		(33 "B.Fab" user "Ref Des/Assembly Bottom")
	)
	(footprint ""
		(layer "F.Cu")
		(at 117.221 -77.089 -90)
		(property "Reference" "R3D9"
			(at 0 0 270)
			(layer "F.SilkS")
			(hide yes)
			(effects
				(font
					(size 1.27 1.27)
				)
			)
		)
		(property "Value" ""
			(at 0 0 270)
			(layer "F.Fab")
			(effects
				(font
					(size 1.27 1.27)
				)
			)
		)
		(duplicate_pad_numbers_are_jumpers no)
		(fp_poly
			(pts
				(xy -0.2794 -0.1016) (xy 0.2794 -0.1016) (xy 0.2794 0.9906) (xy -0.2794 0.9906)
			)
			(stroke
				(width 0)
				(type default)
			)
			(fill no)
			(layer "F.CrtYd")
		)
		(fp_line
			(start -0.2794 0.9906)
			(end 0.2794 0.9906)
			(stroke
				(width 0.1)
				(type default)
			)
			(layer "F.Fab")
		)
		(fp_line
			(start 0.2794 0.9906)
			(end 0.2794 -0.1016)
			(stroke
				(width 0.1)
				(type default)
			)
			(layer "F.Fab")
		)
		(fp_line
			(start -0.2794 -0.1016)
			(end -0.2794 0.9906)
			(stroke
				(width 0.1)
				(type default)
			)
			(layer "F.Fab")
		)
		(fp_line
			(start 0.2794 -0.1016)
			(end -0.2794 -0.1016)
			(stroke
				(width 0.1)
				(type default)
			)
			(layer "F.Fab")
		)
		(pad "1" smd rect
			(at 0 0 270)
			(size 0.508 0.508)
			(layers "F.Cu" "F.Mask" "F.Paste")
			(net "PD_CPU1_TEST12")
		)
		(pad "2" smd rect
			(at 0 0.889 270)
			(size 0.508 0.508)
			(layers "F.Cu" "F.Mask" "F.Paste")
			(net "GND")
		)
		(zone
			(layer "F.Cu")
			(hatch none 0.5)
			(connect_pads
				(clearance 0)
			)
			(min_thickness 0.25)
			(keepout
				(tracks not_allowed)
				(vias allowed)
				(pads allowed)
				(copperpour not_allowed)
				(footprints allowed)
			)
			(placement
				(enabled no)
				(sheetname "")
			)
			(fill
				(thermal_gap 0.5)
				(thermal_bridge_width 0.5)
				(island_removal_mode 0)
			)
			(polygon
				(pts
					(xy 116.586 -77.343) (xy 116.586 -76.835) (xy 116.967 -76.835) (xy 116.967 -77.343)
				)
			)
		)
		(zone
			(layer "F.Cu")
			(hatch none 0.5)
			(connect_pads
				(clearance 0)
			)
			(min_thickness 0.25)
			(keepout
				(tracks allowed)
				(vias not_allowed)
				(pads allowed)
				(copperpour not_allowed)
				(footprints allowed)
			)
			(placement
				(enabled no)
				(sheetname "")
			)
			(fill
				(thermal_gap 0.5)
				(thermal_bridge_width 0.5)
				(island_removal_mode 0)
			)
			(polygon
				(pts
					(xy 116.967 -77.343) (xy 116.967 -76.835) (xy 116.586 -76.835) (xy 116.586 -77.343)
				)
			)
		)
	)
	(footprint ""
		(layer "F.Cu")
		(at 494.1697 -125.03912 90)
		(property "Reference" "R1M8"
			(at 0 0 90)
			(layer "F.SilkS")
			(hide yes)
			(effects
				(font
					(size 1.27 1.27)
				)
			)
		)
		(property "Value" ""
			(at 0 0 90)
			(layer "F.Fab")
			(effects
				(font
					(size 1.27 1.27)
				)
			)
		)
		(duplicate_pad_numbers_are_jumpers no)
		(fp_rect
			(start 0.2794 -0.1016)
			(end -0.2794 0.9906)
			(stroke
				(width 0)
				(type default)
			)
			(fill no)
			(layer "F.CrtYd")
		)
		(fp_line
			(start 0.2794 -0.1016)
			(end -0.2794 -0.1016)
			(stroke
				(width 0.1)
				(type default)
			)
			(layer "F.Fab")
		)
		(fp_line
			(start -0.2794 -0.1016)
			(end -0.2794 0.9906)
			(stroke
				(width 0.1)
				(type default)
			)
			(layer "F.Fab")
		)
		(fp_line
			(start 0.2794 0.9906)
			(end 0.2794 -0.1016)
			(stroke
				(width 0.1)
				(type default)
			)
			(layer "F.Fab")
		)
		(fp_line
			(start -0.2794 0.9906)
			(end 0.2794 0.9906)
			(stroke
				(width 0.1)
				(type default)
			)
			(layer "F.Fab")
		)
		(pad "1" smd rect
			(at 0 0 90)
			(size 0.508 0.508)
			(layers "F.Cu" "F.Mask" "F.Paste")
			(net "SMB_SENSOR_TMP421_1_SCL")
		)
		(pad "2" smd rect
			(at 0 0.889 90)
			(size 0.508 0.508)
			(layers "F.Cu" "F.Mask" "F.Paste")
			(net "SMB_SENSOR_STBY_LVC3_SCL")
		)
		(zone
			(layer "F.Cu")
			(hatch none 0.5)
			(connect_pads
				(clearance 0)
			)
			(min_thickness 0.25)
			(keepout
				(tracks not_allowed)
				(vias allowed)
				(pads allowed)
				(copperpour not_allowed)
				(footprints allowed)
			)
			(placement
				(enabled no)
				(sheetname "")
			)
			(fill
				(thermal_gap 0.5)
				(thermal_bridge_width 0.5)
				(island_removal_mode 0)
			)
			(polygon
				(pts
					(xy 494.4237 -125.29312) (xy 494.4237 -124.78512) (xy 494.8047 -124.78512) (xy 494.8047 -125.29312)
				)
			)
		)
		(zone
			(layer "F.Cu")
			(hatch none 0.5)
			(connect_pads
				(clearance 0)
			)
			(min_thickness 0.25)
			(keepout
				(tracks allowed)
				(vias not_allowed)
				(pads allowed)
				(copperpour not_allowed)
				(footprints allowed)
			)
			(placement
				(enabled no)
				(sheetname "")
			)
			(fill
				(thermal_gap 0.5)
				(thermal_bridge_width 0.5)
				(island_removal_mode 0)
			)
			(polygon
				(pts
					(xy 494.4237 -125.29312) (xy 494.4237 -124.78512) (xy 494.8047 -124.78512) (xy 494.8047 -125.29312)
				)
			)
		)
	)
	(footprint ""
		(layer "F.Cu")
		(at 411.327092 -125.850904 -90)
		(property "Reference" "R8B14"
			(at 0 0 270)
			(layer "F.SilkS")
			(hide yes)
			(effects
				(font
					(size 1.27 1.27)
				)
			)
		)
		(property "Value" ""
			(at 0 0 270)
			(layer "F.Fab")
			(effects
				(font
					(size 1.27 1.27)
				)
			)
		)
		(duplicate_pad_numbers_are_jumpers no)
		(fp_poly
			(pts
				(xy -0.2794 -0.1016) (xy 0.2794 -0.1016) (xy 0.2794 0.9906) (xy -0.2794 0.9906)
			)
			(stroke
				(width 0)
				(type default)
			)
			(fill no)
			(layer "F.CrtYd")
		)
		(fp_line
			(start -0.2794 0.9906)
			(end 0.2794 0.9906)
			(stroke
				(width 0.1)
				(type default)
			)
			(layer "F.Fab")
		)
		(fp_line
			(start 0.2794 0.9906)
			(end 0.2794 -0.1016)
			(stroke
				(width 0.1)
				(type default)
			)
			(layer "F.Fab")
		)
		(fp_line
			(start -0.2794 -0.1016)
			(end -0.2794 0.9906)
			(stroke
				(width 0.1)
				(type default)
			)
			(layer "F.Fab")
		)
		(fp_line
			(start 0.2794 -0.1016)
			(end -0.2794 -0.1016)
			(stroke
				(width 0.1)
				(type default)
			)
			(layer "F.Fab")
		)
		(pad "1" smd rect
			(at 0 0 270)
			(size 0.508 0.508)
			(layers "F.Cu" "F.Mask" "F.Paste")
			(net "VSENSE_P1V05_PCH_STBY_AVSP")
		)
		(pad "2" smd rect
			(at 0 0.889 270)
			(size 0.508 0.508)
			(layers "F.Cu" "F.Mask" "F.Paste")
			(net "P1V05_PCH_STBY")
		)
		(zone
			(layer "F.Cu")
			(hatch none 0.5)
			(connect_pads
				(clearance 0)
			)
			(min_thickness 0.25)
			(keepout
				(tracks not_allowed)
				(vias allowed)
				(pads allowed)
				(copperpour not_allowed)
				(footprints allowed)
			)
			(placement
				(enabled no)
				(sheetname "")
			)
			(fill
				(thermal_gap 0.5)
				(thermal_bridge_width 0.5)
				(island_removal_mode 0)
			)
			(polygon
				(pts
					(xy 410.692092 -126.104904) (xy 410.692092 -125.596904) (xy 411.073092 -125.596904) (xy 411.073092 -126.104904)
				)
			)
		)
		(zone
			(layer "F.Cu")
			(hatch none 0.5)
			(connect_pads
				(clearance 0)
			)
			(min_thickness 0.25)
			(keepout
				(tracks allowed)
				(vias not_allowed)
				(pads allowed)
				(copperpour not_allowed)
				(footprints allowed)
			)
			(placement
				(enabled no)
				(sheetname "")
			)
			(fill
				(thermal_gap 0.5)
				(thermal_bridge_width 0.5)
				(island_removal_mode 0)
			)
			(polygon
				(pts
					(xy 411.073092 -126.104904) (xy 411.073092 -125.596904) (xy 410.692092 -125.596904) (xy 410.692092 -126.104904)
				)
			)
		)
	)
)
